(kicad_pcb
	(version 20260206)
	(generator "pcbnew")
	(generator_version "10.0")
	(general
		(thickness 1.6)
		(legacy_teardrops no)
	)
	(paper "A4")
	(title_block
		(title "01162023_DA0F0TEBIF0_F0T_Expander_BD_F_brd_V02_OCP.brd")
		(comment 1 "Grand Teton / footprints 6002-6008 of 9728")
	)
	(layers
		(0 "F.Cu" signal "TOP")
		(4 "In1.Cu" signal "GND")
		(6 "In2.Cu" signal "VCC")
		(8 "In3.Cu" signal "VCC1")
		(10 "In4.Cu" signal "GND1")
		(12 "In5.Cu" signal "IN1")
		(14 "In6.Cu" signal "GND2")
		(16 "In7.Cu" signal "IN2")
		(18 "In8.Cu" signal "GND3")
		(20 "In9.Cu" signal "IN3")
		(22 "In10.Cu" signal "GND4")
		(24 "In11.Cu" signal "IN4")
		(26 "In12.Cu" signal "GND5")
		(28 "In13.Cu" signal "IN5")
		(30 "In14.Cu" signal "GND6")
		(32 "In15.Cu" signal "IN6")
		(34 "In16.Cu" signal "GND7")
		(2 "B.Cu" signal "BOTTOM")
		(9 "F.Adhes" user "F.Adhesive")
		(11 "B.Adhes" user "B.Adhesive")
		(13 "F.Paste" user "Package Geometry/Pastemask Top")
		(15 "B.Paste" user "Package Geometry/Pastemask Bottom")
		(5 "F.SilkS" user "Ref Des/Silkscreen Top")
		(7 "B.SilkS" user "Ref Des/Silkscreen Bottom")
		(1 "F.Mask" user "Board Geometry/Soldermask Top")
		(3 "B.Mask" user "Board Geometry/Soldermask Bottom")
		(17 "Dwgs.User" user "User.Drawings")
		(19 "Cmts.User" user "User.Comments")
		(21 "Eco1.User" user "User.Eco1")
		(23 "Eco2.User" user "User.Eco2")
		(25 "Edge.Cuts" user "Board Geometry/Outline")
		(27 "Margin" user)
		(31 "F.CrtYd" user "Package Geometry/Place Bound Top")
		(29 "B.CrtYd" user "Package Geometry/Place Bound Bottom")
		(35 "F.Fab" user "Ref Des/Assembly Top")
		(33 "B.Fab" user "Ref Des/Assembly Bottom")
	)
	(footprint ""
		(layer "F.Cu")
		(at 194.125088 -14.735302 180)
		(property "Reference" "C2724"
			(at 0 0 180)
			(layer "F.SilkS")
			(hide yes)
			(effects
				(font
					(size 1.27 1.27)
				)
			)
		)
		(property "Value" ""
			(at 0 0 180)
			(layer "F.Fab")
			(effects
				(font
					(size 1.27 1.27)
				)
			)
		)
		(duplicate_pad_numbers_are_jumpers no)
		(fp_line
			(start 0.7874 0.4064)
			(end -0.7874 0.4064)
			(stroke
				(width 0.1524)
				(type default)
			)
			(layer "F.SilkS")
		)
		(fp_line
			(start 0.7874 -0.4064)
			(end 0.7874 0.4064)
			(stroke
				(width 0.1524)
				(type default)
			)
			(layer "F.SilkS")
		)
		(fp_line
			(start -0.7874 0.4064)
			(end -0.7874 -0.4064)
			(stroke
				(width 0.1524)
				(type default)
			)
			(layer "F.SilkS")
		)
		(fp_line
			(start -0.7874 -0.4064)
			(end 0.7874 -0.4064)
			(stroke
				(width 0.1524)
				(type default)
			)
			(layer "F.SilkS")
		)
		(fp_line
			(start 0.67945 0.3048)
			(end 0.120396 0.3048)
			(stroke
				(width 0.1)
				(type default)
			)
			(layer "F.Fab")
		)
		(fp_line
			(start 0.67945 -0.3048)
			(end 0.67945 0.3048)
			(stroke
				(width 0.1)
				(type default)
			)
			(layer "F.Fab")
		)
		(fp_line
			(start 0.12065 -0.2794)
			(end 0.12065 -0.3048)
			(stroke
				(width 0.1)
				(type default)
			)
			(layer "F.Fab")
		)
		(fp_line
			(start 0.12065 -0.3048)
			(end 0.67945 -0.3048)
			(stroke
				(width 0.1)
				(type default)
			)
			(layer "F.Fab")
		)
		(fp_line
			(start 0.120396 0.3048)
			(end 0.120396 0.2794)
			(stroke
				(width 0.1)
				(type default)
			)
			(layer "F.Fab")
		)
		(fp_line
			(start 0.120396 0.2794)
			(end -0.12065 0.2794)
			(stroke
				(width 0.1)
				(type default)
			)
			(layer "F.Fab")
		)
		(fp_line
			(start -0.12065 0.3048)
			(end -0.67945 0.3048)
			(stroke
				(width 0.1)
				(type default)
			)
			(layer "F.Fab")
		)
		(fp_line
			(start -0.12065 0.2794)
			(end -0.12065 0.3048)
			(stroke
				(width 0.1)
				(type default)
			)
			(layer "F.Fab")
		)
		(fp_line
			(start -0.12065 -0.2794)
			(end 0.12065 -0.2794)
			(stroke
				(width 0.1)
				(type default)
			)
			(layer "F.Fab")
		)
		(fp_line
			(start -0.12065 -0.305054)
			(end -0.12065 -0.2794)
			(stroke
				(width 0.1)
				(type default)
			)
			(layer "F.Fab")
		)
		(fp_line
			(start -0.67945 0.3048)
			(end -0.67945 -0.305054)
			(stroke
				(width 0.1)
				(type default)
			)
			(layer "F.Fab")
		)
		(fp_line
			(start -0.67945 -0.305054)
			(end -0.12065 -0.305054)
			(stroke
				(width 0.1)
				(type default)
			)
			(layer "F.Fab")
		)
		(pad "1" smd circle
			(at -0.40005 0 180)
			(size 0 0)
			(layers "F.Cu" "F.Mask" "F.Paste")
			(net "GND")
		)
		(pad "2" smd circle
			(at 0.40005 0 180)
			(size 0 0)
			(layers "F.Cu" "F.Mask" "F.Paste")
			(net "P3V3_SSD6")
		)
	)
	(footprint ""
		(layer "F.Cu")
		(at 284.6451 -175.182276)
		(property "Reference" "R255"
			(at 0 0 0)
			(layer "F.SilkS")
			(hide yes)
			(effects
				(font
					(size 1.27 1.27)
				)
			)
		)
		(property "Value" ""
			(at 0 0 0)
			(layer "F.Fab")
			(effects
				(font
					(size 1.27 1.27)
				)
			)
		)
		(duplicate_pad_numbers_are_jumpers no)
		(fp_line
			(start -0.7874 -0.4064)
			(end 0.7874 -0.4064)
			(stroke
				(width 0.1524)
				(type default)
			)
			(layer "F.SilkS")
		)
		(fp_line
			(start -0.7874 0.4064)
			(end -0.7874 -0.4064)
			(stroke
				(width 0.1524)
				(type default)
			)
			(layer "F.SilkS")
		)
		(fp_line
			(start 0.7874 -0.4064)
			(end 0.7874 0.4064)
			(stroke
				(width 0.1524)
				(type default)
			)
			(layer "F.SilkS")
		)
		(fp_line
			(start 0.7874 0.4064)
			(end -0.7874 0.4064)
			(stroke
				(width 0.1524)
				(type default)
			)
			(layer "F.SilkS")
		)
		(fp_line
			(start -0.67945 -0.305054)
			(end -0.12065 -0.305054)
			(stroke
				(width 0.1)
				(type default)
			)
			(layer "F.Fab")
		)
		(fp_line
			(start -0.67945 0.3048)
			(end -0.67945 -0.305054)
			(stroke
				(width 0.1)
				(type default)
			)
			(layer "F.Fab")
		)
		(fp_line
			(start -0.12065 -0.305054)
			(end -0.12065 -0.2794)
			(stroke
				(width 0.1)
				(type default)
			)
			(layer "F.Fab")
		)
		(fp_line
			(start -0.12065 -0.2794)
			(end 0.12065 -0.2794)
			(stroke
				(width 0.1)
				(type default)
			)
			(layer "F.Fab")
		)
		(fp_line
			(start -0.12065 0.2794)
			(end -0.12065 0.3048)
			(stroke
				(width 0.1)
				(type default)
			)
			(layer "F.Fab")
		)
		(fp_line
			(start -0.12065 0.3048)
			(end -0.67945 0.3048)
			(stroke
				(width 0.1)
				(type default)
			)
			(layer "F.Fab")
		)
		(fp_line
			(start 0.120396 0.2794)
			(end -0.12065 0.2794)
			(stroke
				(width 0.1)
				(type default)
			)
			(layer "F.Fab")
		)
		(fp_line
			(start 0.120396 0.3048)
			(end 0.120396 0.2794)
			(stroke
				(width 0.1)
				(type default)
			)
			(layer "F.Fab")
		)
		(fp_line
			(start 0.12065 -0.3048)
			(end 0.67945 -0.3048)
			(stroke
				(width 0.1)
				(type default)
			)
			(layer "F.Fab")
		)
		(fp_line
			(start 0.12065 -0.2794)
			(end 0.12065 -0.3048)
			(stroke
				(width 0.1)
				(type default)
			)
			(layer "F.Fab")
		)
		(fp_line
			(start 0.67945 -0.3048)
			(end 0.67945 0.3048)
			(stroke
				(width 0.1)
				(type default)
			)
			(layer "F.Fab")
		)
		(fp_line
			(start 0.67945 0.3048)
			(end 0.120396 0.3048)
			(stroke
				(width 0.1)
				(type default)
			)
			(layer "F.Fab")
		)
		(pad "1" smd circle
			(at -0.40005 0)
			(size 0 0)
			(layers "F.Cu" "F.Mask" "F.Paste")
			(net "HP_NIC4_PWRGD_R")
		)
		(pad "2" smd circle
			(at 0.40005 0)
			(size 0 0)
			(layers "F.Cu" "F.Mask" "F.Paste")
			(net "HP_NIC4_PWRGD")
		)
	)
	(footprint ""
		(layer "F.Cu")
		(at 341.372444 -350.098614 90)
		(property "Reference" "C578"
			(at 0 0 90)
			(layer "F.SilkS")
			(hide yes)
			(effects
				(font
					(size 1.27 1.27)
				)
			)
		)
		(property "Value" ""
			(at 0 0 90)
			(layer "F.Fab")
			(effects
				(font
					(size 1.27 1.27)
				)
			)
		)
		(duplicate_pad_numbers_are_jumpers no)
		(fp_line
			(start 0.299974 -0.150114)
			(end 0.299974 0.150114)
			(stroke
				(width 0.1)
				(type default)
			)
			(layer "F.Fab")
		)
		(fp_line
			(start -0.299974 -0.150114)
			(end 0.299974 -0.150114)
			(stroke
				(width 0.1)
				(type default)
			)
			(layer "F.Fab")
		)
		(fp_line
			(start 0.299974 0.150114)
			(end -0.299974 0.150114)
			(stroke
				(width 0.1)
				(type default)
			)
			(layer "F.Fab")
		)
		(fp_line
			(start -0.299974 0.150114)
			(end -0.299974 -0.150114)
			(stroke
				(width 0.1)
				(type default)
			)
			(layer "F.Fab")
		)
		(pad "1" smd rect
			(at -0.2667 0 90)
			(size 0.3048 0.381)
			(layers "F.Cu" "F.Mask" "F.Paste")
			(net "P5E_PEX2_STN6_TX_DN<98>")
		)
		(pad "2" smd rect
			(at 0.2667 0 90)
			(size 0.3048 0.381)
			(layers "F.Cu" "F.Mask" "F.Paste")
			(net "P5E_PEX2_STN6_TX_C_DN<98>")
		)
	)
	(footprint ""
		(layer "F.Cu")
		(at 282.681934 -38.041072 180)
		(property "Reference" "R6096"
			(at 0 0 180)
			(layer "F.SilkS")
			(hide yes)
			(effects
				(font
					(size 1.27 1.27)
				)
			)
		)
		(property "Value" ""
			(at 0 0 180)
			(layer "F.Fab")
			(effects
				(font
					(size 1.27 1.27)
				)
			)
		)
		(duplicate_pad_numbers_are_jumpers no)
		(fp_line
			(start 0.7874 0.4064)
			(end -0.7874 0.4064)
			(stroke
				(width 0.1524)
				(type default)
			)
			(layer "F.SilkS")
		)
		(fp_line
			(start 0.7874 -0.4064)
			(end 0.7874 0.4064)
			(stroke
				(width 0.1524)
				(type default)
			)
			(layer "F.SilkS")
		)
		(fp_line
			(start -0.7874 0.4064)
			(end -0.7874 -0.4064)
			(stroke
				(width 0.1524)
				(type default)
			)
			(layer "F.SilkS")
		)
		(fp_line
			(start -0.7874 -0.4064)
			(end 0.7874 -0.4064)
			(stroke
				(width 0.1524)
				(type default)
			)
			(layer "F.SilkS")
		)
		(fp_line
			(start 0.67945 0.3048)
			(end 0.120396 0.3048)
			(stroke
				(width 0.1)
				(type default)
			)
			(layer "F.Fab")
		)
		(fp_line
			(start 0.67945 -0.3048)
			(end 0.67945 0.3048)
			(stroke
				(width 0.1)
				(type default)
			)
			(layer "F.Fab")
		)
		(fp_line
			(start 0.12065 -0.2794)
			(end 0.12065 -0.3048)
			(stroke
				(width 0.1)
				(type default)
			)
			(layer "F.Fab")
		)
		(fp_line
			(start 0.12065 -0.3048)
			(end 0.67945 -0.3048)
			(stroke
				(width 0.1)
				(type default)
			)
			(layer "F.Fab")
		)
		(fp_line
			(start 0.120396 0.3048)
			(end 0.120396 0.2794)
			(stroke
				(width 0.1)
				(type default)
			)
			(layer "F.Fab")
		)
		(fp_line
			(start 0.120396 0.2794)
			(end -0.12065 0.2794)
			(stroke
				(width 0.1)
				(type default)
			)
			(layer "F.Fab")
		)
		(fp_line
			(start -0.12065 0.3048)
			(end -0.67945 0.3048)
			(stroke
				(width 0.1)
				(type default)
			)
			(layer "F.Fab")
		)
		(fp_line
			(start -0.12065 0.2794)
			(end -0.12065 0.3048)
			(stroke
				(width 0.1)
				(type default)
			)
			(layer "F.Fab")
		)
		(fp_line
			(start -0.12065 -0.2794)
			(end 0.12065 -0.2794)
			(stroke
				(width 0.1)
				(type default)
			)
			(layer "F.Fab")
		)
		(fp_line
			(start -0.12065 -0.305054)
			(end -0.12065 -0.2794)
			(stroke
				(width 0.1)
				(type default)
			)
			(layer "F.Fab")
		)
		(fp_line
			(start -0.67945 0.3048)
			(end -0.67945 -0.305054)
			(stroke
				(width 0.1)
				(type default)
			)
			(layer "F.Fab")
		)
		(fp_line
			(start -0.67945 -0.305054)
			(end -0.12065 -0.305054)
			(stroke
				(width 0.1)
				(type default)
			)
			(layer "F.Fab")
		)
		(pad "1" smd circle
			(at -0.40005 0 180)
			(size 0 0)
			(layers "F.Cu" "F.Mask" "F.Paste")
			(net "P5V_AUX")
		)
		(pad "2" smd circle
			(at 0.40005 0 180)
			(size 0 0)
			(layers "F.Cu" "F.Mask" "F.Paste")
			(net "P3V3_SSD10_PG_G2")
		)
	)
	(footprint ""
		(layer "F.Cu")
		(at 248.094754 -278.551386)
		(property "Reference" "R790"
			(at 0 0 0)
			(layer "F.SilkS")
			(hide yes)
			(effects
				(font
					(size 1.27 1.27)
				)
			)
		)
		(property "Value" ""
			(at 0 0 0)
			(layer "F.Fab")
			(effects
				(font
					(size 1.27 1.27)
				)
			)
		)
		(duplicate_pad_numbers_are_jumpers no)
		(fp_line
			(start -0.7874 -0.4064)
			(end 0.7874 -0.4064)
			(stroke
				(width 0.1524)
				(type default)
			)
			(layer "F.SilkS")
		)
		(fp_line
			(start -0.7874 0.4064)
			(end -0.7874 -0.4064)
			(stroke
				(width 0.1524)
				(type default)
			)
			(layer "F.SilkS")
		)
		(fp_line
			(start 0.7874 -0.4064)
			(end 0.7874 0.4064)
			(stroke
				(width 0.1524)
				(type default)
			)
			(layer "F.SilkS")
		)
		(fp_line
			(start 0.7874 0.4064)
			(end -0.7874 0.4064)
			(stroke
				(width 0.1524)
				(type default)
			)
			(layer "F.SilkS")
		)
		(fp_line
			(start -0.67945 -0.305054)
			(end -0.12065 -0.305054)
			(stroke
				(width 0.1)
				(type default)
			)
			(layer "F.Fab")
		)
		(fp_line
			(start -0.67945 0.3048)
			(end -0.67945 -0.305054)
			(stroke
				(width 0.1)
				(type default)
			)
			(layer "F.Fab")
		)
		(fp_line
			(start -0.12065 -0.305054)
			(end -0.12065 -0.2794)
			(stroke
				(width 0.1)
				(type default)
			)
			(layer "F.Fab")
		)
		(fp_line
			(start -0.12065 -0.2794)
			(end 0.12065 -0.2794)
			(stroke
				(width 0.1)
				(type default)
			)
			(layer "F.Fab")
		)
		(fp_line
			(start -0.12065 0.2794)
			(end -0.12065 0.3048)
			(stroke
				(width 0.1)
				(type default)
			)
			(layer "F.Fab")
		)
		(fp_line
			(start -0.12065 0.3048)
			(end -0.67945 0.3048)
			(stroke
				(width 0.1)
				(type default)
			)
			(layer "F.Fab")
		)
		(fp_line
			(start 0.120396 0.2794)
			(end -0.12065 0.2794)
			(stroke
				(width 0.1)
				(type default)
			)
			(layer "F.Fab")
		)
		(fp_line
			(start 0.120396 0.3048)
			(end 0.120396 0.2794)
			(stroke
				(width 0.1)
				(type default)
			)
			(layer "F.Fab")
		)
		(fp_line
			(start 0.12065 -0.3048)
			(end 0.67945 -0.3048)
			(stroke
				(width 0.1)
				(type default)
			)
			(layer "F.Fab")
		)
		(fp_line
			(start 0.12065 -0.2794)
			(end 0.12065 -0.3048)
			(stroke
				(width 0.1)
				(type default)
			)
			(layer "F.Fab")
		)
		(fp_line
			(start 0.67945 -0.3048)
			(end 0.67945 0.3048)
			(stroke
				(width 0.1)
				(type default)
			)
			(layer "F.Fab")
		)
		(fp_line
			(start 0.67945 0.3048)
			(end 0.120396 0.3048)
			(stroke
				(width 0.1)
				(type default)
			)
			(layer "F.Fab")
		)
		(pad "1" smd circle
			(at -0.40005 0)
			(size 0 0)
			(layers "F.Cu" "F.Mask" "F.Paste")
			(net "P3V3_AUX")
		)
		(pad "2" smd circle
			(at 0.40005 0)
			(size 0 0)
			(layers "F.Cu" "F.Mask" "F.Paste")
			(net "PEX_ADC_ALERT_N")
		)
	)
	(footprint ""
		(layer "F.Cu")
		(at 356.410514 -63.652146 180)
		(property "Reference" "R6016"
			(at 0 0 180)
			(layer "F.SilkS")
			(hide yes)
			(effects
				(font
					(size 1.27 1.27)
				)
			)
		)
		(property "Value" ""
			(at 0 0 180)
			(layer "F.Fab")
			(effects
				(font
					(size 1.27 1.27)
				)
			)
		)
		(duplicate_pad_numbers_are_jumpers no)
		(fp_line
			(start 0.7874 0.4064)
			(end -0.7874 0.4064)
			(stroke
				(width 0.1524)
				(type default)
			)
			(layer "F.SilkS")
		)
		(fp_line
			(start 0.7874 -0.4064)
			(end 0.7874 0.4064)
			(stroke
				(width 0.1524)
				(type default)
			)
			(layer "F.SilkS")
		)
		(fp_line
			(start -0.7874 0.4064)
			(end -0.7874 -0.4064)
			(stroke
				(width 0.1524)
				(type default)
			)
			(layer "F.SilkS")
		)
		(fp_line
			(start -0.7874 -0.4064)
			(end 0.7874 -0.4064)
			(stroke
				(width 0.1524)
				(type default)
			)
			(layer "F.SilkS")
		)
		(fp_line
			(start 0.67945 0.3048)
			(end 0.120396 0.3048)
			(stroke
				(width 0.1)
				(type default)
			)
			(layer "F.Fab")
		)
		(fp_line
			(start 0.67945 -0.3048)
			(end 0.67945 0.3048)
			(stroke
				(width 0.1)
				(type default)
			)
			(layer "F.Fab")
		)
		(fp_line
			(start 0.12065 -0.2794)
			(end 0.12065 -0.3048)
			(stroke
				(width 0.1)
				(type default)
			)
			(layer "F.Fab")
		)
		(fp_line
			(start 0.12065 -0.3048)
			(end 0.67945 -0.3048)
			(stroke
				(width 0.1)
				(type default)
			)
			(layer "F.Fab")
		)
		(fp_line
			(start 0.120396 0.3048)
			(end 0.120396 0.2794)
			(stroke
				(width 0.1)
				(type default)
			)
			(layer "F.Fab")
		)
		(fp_line
			(start 0.120396 0.2794)
			(end -0.12065 0.2794)
			(stroke
				(width 0.1)
				(type default)
			)
			(layer "F.Fab")
		)
		(fp_line
			(start -0.12065 0.3048)
			(end -0.67945 0.3048)
			(stroke
				(width 0.1)
				(type default)
			)
			(layer "F.Fab")
		)
		(fp_line
			(start -0.12065 0.2794)
			(end -0.12065 0.3048)
			(stroke
				(width 0.1)
				(type default)
			)
			(layer "F.Fab")
		)
		(fp_line
			(start -0.12065 -0.2794)
			(end 0.12065 -0.2794)
			(stroke
				(width 0.1)
				(type default)
			)
			(layer "F.Fab")
		)
		(fp_line
			(start -0.12065 -0.305054)
			(end -0.12065 -0.2794)
			(stroke
				(width 0.1)
				(type default)
			)
			(layer "F.Fab")
		)
		(fp_line
			(start -0.67945 0.3048)
			(end -0.67945 -0.305054)
			(stroke
				(width 0.1)
				(type default)
			)
			(layer "F.Fab")
		)
		(fp_line
			(start -0.67945 -0.305054)
			(end -0.12065 -0.305054)
			(stroke
				(width 0.1)
				(type default)
			)
			(layer "F.Fab")
		)
		(pad "1" smd circle
			(at -0.40005 0 180)
			(size 0 0)
			(layers "F.Cu" "F.Mask" "F.Paste")
			(net "P5V_AUX")
		)
		(pad "2" smd circle
			(at 0.40005 0 180)
			(size 0 0)
			(layers "F.Cu" "F.Mask" "F.Paste")
			(net "P12V_SSD12_PG_G2")
		)
	)
	(footprint ""
		(layer "F.Cu")
		(at 328.146918 -55.63489 90)
		(property "Reference" "PC441"
			(at 0 0 90)
			(layer "F.SilkS")
			(hide yes)
			(effects
				(font
					(size 1.27 1.27)
				)
			)
		)
		(property "Value" ""
			(at 0 0 90)
			(layer "F.Fab")
			(effects
				(font
					(size 1.27 1.27)
				)
			)
		)
		(duplicate_pad_numbers_are_jumpers no)
		(fp_line
			(start 1.524 -0.762)
			(end 1.524 0.762)
			(stroke
				(width 0.1524)
				(type default)
			)
			(layer "F.SilkS")
		)
		(fp_line
			(start -1.524 -0.762)
			(end 1.524 -0.762)
			(stroke
				(width 0.1524)
				(type default)
			)
			(layer "F.SilkS")
		)
		(fp_line
			(start 1.524 0.762)
			(end -1.524 0.762)
			(stroke
				(width 0.1524)
				(type default)
			)
			(layer "F.SilkS")
		)
		(fp_line
			(start -1.524 0.762)
			(end -1.524 -0.762)
			(stroke
				(width 0.1524)
				(type default)
			)
			(layer "F.SilkS")
		)
		(fp_line
			(start 1.1049 -0.724916)
			(end -1.1049 -0.724916)
			(stroke
				(width 0.1)
				(type default)
			)
			(layer "F.Fab")
		)
		(fp_line
			(start -1.1049 -0.724916)
			(end -1.1049 0.724916)
			(stroke
				(width 0.1)
				(type default)
			)
			(layer "F.Fab")
		)
		(fp_line
			(start 1.1049 0.724916)
			(end 1.1049 -0.724916)
			(stroke
				(width 0.1)
				(type default)
			)
			(layer "F.Fab")
		)
		(fp_line
			(start -1.1049 0.724916)
			(end 1.1049 0.724916)
			(stroke
				(width 0.1)
				(type default)
			)
			(layer "F.Fab")
		)
		(pad "1" smd rect
			(at -0.889 0 270)
			(size 1.016 1.27)
			(layers "F.Cu" "F.Mask" "F.Paste")
			(net "P12V_SSD11_R")
		)
		(pad "2" smd rect
			(at 0.889 0 270)
			(size 1.016 1.27)
			(layers "F.Cu" "F.Mask" "F.Paste")
			(net "GND")
		)
	)
)
